(kicad_pcb
	(version 20241229)
	(generator "pcbnew")
	(generator_version "9.0")
	(general
		(thickness 1.63)
		(legacy_teardrops no)
	)
	(paper "A4")
	(title_block
		(title "CM4 Baseboard")
		(date "2026-01-05")
		(rev "1.1.1")
		(company "Antmicro Ltd")
		(comment 1 "www.antmicro.com")
		(comment 9 "footprints 437-440 of 506")
	)
	(layers
		(0 "F.Cu" signal)
		(4 "In1.Cu" power)
		(6 "In2.Cu" power)
		(8 "In3.Cu" signal)
		(10 "In4.Cu" signal)
		(2 "B.Cu" signal)
		(9 "F.Adhes" user "F.Adhesive")
		(11 "B.Adhes" user "B.Adhesive")
		(13 "F.Paste" user)
		(15 "B.Paste" user)
		(5 "F.SilkS" user "F.Silkscreen")
		(7 "B.SilkS" user "B.Silkscreen")
		(1 "F.Mask" user)
		(3 "B.Mask" user)
		(17 "Dwgs.User" user "User.Drawings")
		(19 "Cmts.User" user "User.Comments")
		(21 "Eco1.User" user "User.Eco1")
		(23 "Eco2.User" user "User.Eco2")
		(25 "Edge.Cuts" user)
		(27 "Margin" user)
		(31 "F.CrtYd" user "F.Courtyard")
		(29 "B.CrtYd" user "B.Courtyard")
		(35 "F.Fab" user)
		(33 "B.Fab" user)
	)
	(footprint "antmicro-footprints:C_0402_1005Metric"
		(layer "B.Cu")
		(at 113.817962 118.3665)
		(descr "Capacitor SMD 0402")
		(tags "capacitor SMD 0402")
		(property "Reference" "C702"
			(at -0.78 5.69 0)
			(layer "B.SilkS")
			(effects
				(font
					(size 0.7 0.7)
					(thickness 0.15)
				)
				(justify right bottom mirror)
			)
		)
		(property "Value" "C_10u_0402"
			(at -1.022927 -2.155213 0)
			(layer "B.Fab")
			(effects
				(font
					(size 0.7 0.7)
					(thickness 0.15)
				)
				(justify right bottom mirror)
			)
		)
		(property "Datasheet" "https://www.yageo.com/en/Chart/Download/pdf/CC0402MRX5R5BB106"
			(at 0 0 0)
			(layer "B.Fab")
			(hide yes)
			(effects
				(font
					(size 1.27 1.27)
					(thickness 0.15)
				)
			)
		)
		(property "MPN" "CC0402MRX5R5BB106"
			(at 0 0 0)
			(unlocked yes)
			(layer "B.Fab")
			(hide yes)
			(effects
				(font
					(size 1 1)
					(thickness 0.15)
				)
				(justify mirror)
			)
		)
		(property "Manufacturer" "YAGEO"
			(at 0 0 0)
			(unlocked yes)
			(layer "B.Fab")
			(hide yes)
			(effects
				(font
					(size 1 1)
					(thickness 0.15)
				)
				(justify mirror)
			)
		)
		(property "License" "Apache-2.0"
			(at 0 0 0)
			(unlocked yes)
			(layer "B.Fab")
			(hide yes)
			(effects
				(font
					(size 1 1)
					(thickness 0.15)
				)
				(justify mirror)
			)
		)
		(property "Author" "Antmicro"
			(at 0 0 0)
			(unlocked yes)
			(layer "B.Fab")
			(hide yes)
			(effects
				(font
					(size 1 1)
					(thickness 0.15)
				)
				(justify mirror)
			)
		)
		(property "Val" "10u"
			(at 0 0 0)
			(unlocked yes)
			(layer "B.Fab")
			(hide yes)
			(effects
				(font
					(size 1 1)
					(thickness 0.15)
				)
				(justify mirror)
			)
		)
		(property "Voltage" ""
			(at 0 0 0)
			(unlocked yes)
			(layer "B.Fab")
			(hide yes)
			(effects
				(font
					(size 1 1)
					(thickness 0.15)
				)
				(justify mirror)
			)
		)
		(property "Dielectric" ""
			(at 0 0 0)
			(unlocked yes)
			(layer "B.Fab")
			(hide yes)
			(effects
				(font
					(size 1 1)
					(thickness 0.15)
				)
				(justify mirror)
			)
		)
		(sheetname "/Display/")
		(sheetfile "display.kicad_sch")
		(attr smd)
		(fp_rect
			(start -0.925 0.47)
			(end 0.925 -0.47)
			(stroke
				(width 0.05)
				(type default)
			)
			(fill no)
			(layer "B.CrtYd")
		)
		(fp_line
			(start -0.494 -0.248)
			(end -0.494 0.25)
			(stroke
				(width 0.15)
				(type solid)
			)
			(layer "B.Fab")
		)
		(fp_line
			(start -0.494 0.25)
			(end 0.504 0.25)
			(stroke
				(width 0.15)
				(type solid)
			)
			(layer "B.Fab")
		)
		(fp_line
			(start 0.504 -0.248)
			(end -0.494 -0.248)
			(stroke
				(width 0.15)
				(type solid)
			)
			(layer "B.Fab")
		)
		(fp_line
			(start 0.504 0.25)
			(end 0.504 -0.248)
			(stroke
				(width 0.15)
				(type solid)
			)
			(layer "B.Fab")
		)
		(fp_text user "Author: Antmicro"
			(at -0.939 -3.399 180)
			(layer "B.Fab")
			(effects
				(font
					(size 0.7 0.7)
					(thickness 0.15)
				)
				(justify left bottom mirror)
			)
		)
		(fp_text user "License: Apache-2.0"
			(at -0.939 -5.799 180)
			(layer "B.Fab")
			(effects
				(font
					(size 0.7 0.7)
					(thickness 0.15)
				)
				(justify left bottom mirror)
			)
		)
		(fp_text user "${REFERENCE}"
			(at -0.939 -4.599 180)
			(layer "B.Fab")
			(effects
				(font
					(size 0.7 0.7)
					(thickness 0.15)
				)
				(justify left bottom mirror)
			)
		)
		(pad "1" smd roundrect
			(at -0.48 0)
			(size 0.59 0.64)
			(layers "B.Cu" "B.Mask" "B.Paste")
			(roundrect_rratio 0.25)
			(net 3 "GND")
			(pintype "passive")
		)
		(pad "2" smd roundrect
			(at 0.48 0)
			(size 0.59 0.64)
			(layers "B.Cu" "B.Mask" "B.Paste")
			(roundrect_rratio 0.25)
			(net 119 "Net-(D710-C)")
			(pintype "passive")
		)
	)
	(footprint "antmicro-footprints:Nexperia_DFN-10_2.5x1mm_P0.5mm"
		(layer "B.Cu")
		(at 126.467962 166.9915 90)
		(property "Reference" "D501"
			(at -1.365 -1.7 90)
			(layer "B.SilkS")
			(effects
				(font
					(size 0.7 0.7)
					(thickness 0.15)
				)
				(justify right bottom mirror)
			)
		)
		(property "Value" "PUSB3F96X_PASS"
			(at -0.016 -1.705 90)
			(layer "B.Fab")
			(effects
				(font
					(size 0.7 0.7)
					(thickness 0.15)
				)
				(justify right bottom mirror)
			)
		)
		(property "Datasheet" "https://mouser.com/datasheet/2/916/PUSB3F96-1600324.pdf"
			(at 0 0 90)
			(layer "B.Fab")
			(hide yes)
			(effects
				(font
					(size 1.27 1.27)
					(thickness 0.15)
				)
			)
		)
		(property "Manufacturer" "Nexperia"
			(at 0 0 90)
			(unlocked yes)
			(layer "B.Fab")
			(hide yes)
			(effects
				(font
					(size 1 1)
					(thickness 0.15)
				)
				(justify mirror)
			)
		)
		(property "MPN" "PUSB3F96X"
			(at 0 0 90)
			(unlocked yes)
			(layer "B.Fab")
			(hide yes)
			(effects
				(font
					(size 1 1)
					(thickness 0.15)
				)
				(justify mirror)
			)
		)
		(property "Author" "Antmicro"
			(at 0 0 90)
			(unlocked yes)
			(layer "B.Fab")
			(hide yes)
			(effects
				(font
					(size 1 1)
					(thickness 0.15)
				)
				(justify mirror)
			)
		)
		(property "License" "Apache-2.0"
			(at 0 0 90)
			(unlocked yes)
			(layer "B.Fab")
			(hide yes)
			(effects
				(font
					(size 1 1)
					(thickness 0.15)
				)
				(justify mirror)
			)
		)
		(sheetname "/NVMe & microSD/")
		(sheetfile "nvme-micro-sd.kicad_sch")
		(attr smd)
		(fp_line
			(start 1.375 -0.4)
			(end 1.375 0.4)
			(stroke
				(width 0.15)
				(type solid)
			)
			(layer "B.SilkS")
		)
		(fp_line
			(start -1.375 0.4)
			(end -1.375 -0.4)
			(stroke
				(width 0.15)
				(type solid)
			)
			(layer "B.SilkS")
		)
		(fp_circle
			(center -1.4 -0.7)
			(end -1.349 -0.7)
			(stroke
				(width 0.15)
				(type solid)
			)
			(fill yes)
			(layer "B.SilkS")
		)
		(fp_rect
			(start -1.4 0.725)
			(end 1.4 -0.725)
			(stroke
				(width 0.05)
				(type solid)
			)
			(fill no)
			(layer "B.CrtYd")
		)
		(fp_line
			(start 1.25 -0.5)
			(end 1.25 0.5)
			(stroke
				(width 0.15)
				(type solid)
			)
			(layer "B.Fab")
		)
		(fp_line
			(start -0.9 -0.5)
			(end 1.25 -0.5)
			(stroke
				(width 0.15)
				(type solid)
			)
			(layer "B.Fab")
		)
		(fp_line
			(start -1.25 -0.15)
			(end -0.9 -0.5)
			(stroke
				(width 0.15)
				(type solid)
			)
			(layer "B.Fab")
		)
		(fp_line
			(start 1.25 0.5)
			(end -1.25 0.5)
			(stroke
				(width 0.15)
				(type solid)
			)
			(layer "B.Fab")
		)
		(fp_line
			(start -1.25 0.5)
			(end -1.25 -0.15)
			(stroke
				(width 0.15)
				(type solid)
			)
			(layer "B.Fab")
		)
		(fp_text user "${REFERENCE}"
			(at -1.367 -3.704 270)
			(layer "B.Fab")
			(effects
				(font
					(size 0.7 0.7)
					(thickness 0.15)
				)
				(justify left bottom mirror)
			)
		)
		(fp_text user "License: Apache-2.0"
			(at -1.367 -6.105 270)
			(layer "B.Fab")
			(effects
				(font
					(size 0.7 0.7)
					(thickness 0.15)
				)
				(justify left bottom mirror)
			)
		)
		(fp_text user "Author: Antmicro"
			(at -1.367 -4.905 270)
			(layer "B.Fab")
			(effects
				(font
					(size 0.7 0.7)
					(thickness 0.15)
				)
				(justify left bottom mirror)
			)
		)
		(pad "1" smd rect
			(at -1 -0.3875 90)
			(size 0.2 0.475)
			(layers "B.Cu" "B.Mask" "B.Paste")
			(net 118 "/Compute module/SDIO.CD")
			(pinfunction "CH1")
			(pintype "passive")
			(solder_mask_margin 0.05)
		)
		(pad "2" smd rect
			(at -0.5 -0.3875 90)
			(size 0.2 0.475)
			(layers "B.Cu" "B.Mask" "B.Paste")
			(net 12 "/Compute module/SDIO.D2")
			(pinfunction "CH2")
			(pintype "passive")
			(solder_mask_margin 0.05)
		)
		(pad "3" smd rect
			(at 0 -0.3875 90)
			(size 0.2 0.475)
			(layers "B.Cu" "B.Mask" "B.Paste")
			(net 3 "GND")
			(pinfunction "GND")
			(pintype "passive")
			(solder_mask_margin 0.05)
		)
		(pad "4" smd rect
			(at 0.5 -0.3875 90)
			(size 0.2 0.475)
			(layers "B.Cu" "B.Mask" "B.Paste")
			(net 11 "/Compute module/SDIO.D3")
			(pinfunction "CH3")
			(pintype "passive")
			(solder_mask_margin 0.05)
		)
		(pad "5" smd rect
			(at 1 -0.3875 90)
			(size 0.2 0.475)
			(layers "B.Cu" "B.Mask" "B.Paste")
			(net 8 "/Compute module/SDIO.CMD")
			(pinfunction "CH4")
			(pintype "passive")
			(solder_mask_margin 0.05)
		)
		(pad "6" smd rect
			(at 1 0.3875 90)
			(size 0.2 0.475)
			(layers "B.Cu" "B.Mask" "B.Paste")
			(net 8 "/Compute module/SDIO.CMD")
			(pinfunction "CH4")
			(pintype "passive")
			(solder_mask_margin 0.05)
		)
		(pad "7" smd rect
			(at 0.5 0.3875 90)
			(size 0.2 0.475)
			(layers "B.Cu" "B.Mask" "B.Paste")
			(net 11 "/Compute module/SDIO.D3")
			(pinfunction "CH3")
			(pintype "passive")
			(solder_mask_margin 0.05)
		)
		(pad "8" smd rect
			(at 0 0.3875 90)
			(size 0.2 0.475)
			(layers "B.Cu" "B.Mask" "B.Paste")
			(net 3 "GND")
			(pinfunction "GND")
			(pintype "passive")
			(solder_mask_margin 0.05)
		)
		(pad "9" smd rect
			(at -0.501 0.3875 90)
			(size 0.2 0.475)
			(layers "B.Cu" "B.Mask" "B.Paste")
			(net 12 "/Compute module/SDIO.D2")
			(pinfunction "CH2")
			(pintype "passive")
			(solder_mask_margin 0.05)
		)
		(pad "10" smd rect
			(at -1 0.3875 90)
			(size 0.2 0.475)
			(layers "B.Cu" "B.Mask" "B.Paste")
			(net 118 "/Compute module/SDIO.CD")
			(pinfunction "CH1")
			(pintype "passive")
			(solder_mask_margin 0.05)
		)
	)
	(footprint "antmicro-footprints:C_2220_5650Metric"
		(layer "B.Cu")
		(at 61.067962 145.6465 90)
		(descr "Capacitor SMD 2220")
		(tags "capacitor SMD 2220")
		(property "Reference" "C406"
			(at -4.58 -1.42 180)
			(layer "B.SilkS")
			(effects
				(font
					(size 0.7 0.7)
					(thickness 0.15)
				)
				(justify right bottom mirror)
			)
		)
		(property "Value" "C_22u_100V_2220"
			(at 0 -3.9 90)
			(layer "B.Fab")
			(effects
				(font
					(size 0.7 0.7)
					(thickness 0.15)
				)
				(justify right bottom mirror)
			)
		)
		(property "Datasheet" "https://product.tdk.com/en/search/capacitor/ceramic/mlcc/info?part_no=C5750X7S2A226M280KB"
			(at 0 0 90)
			(layer "B.Fab")
			(hide yes)
			(effects
				(font
					(size 1.27 1.27)
					(thickness 0.15)
				)
			)
		)
		(property "Manufacturer" "TDK"
			(at 0 0 90)
			(unlocked yes)
			(layer "B.Fab")
			(hide yes)
			(effects
				(font
					(size 1 1)
					(thickness 0.15)
				)
				(justify mirror)
			)
		)
		(property "MPN" "C5750X7S2A226M280KB"
			(at 0 0 90)
			(unlocked yes)
			(layer "B.Fab")
			(hide yes)
			(effects
				(font
					(size 1 1)
					(thickness 0.15)
				)
				(justify mirror)
			)
		)
		(property "Val" "22u"
			(at 0 0 90)
			(unlocked yes)
			(layer "B.Fab")
			(hide yes)
			(effects
				(font
					(size 1 1)
					(thickness 0.15)
				)
				(justify mirror)
			)
		)
		(property "License" "Apache-2.0"
			(at 0 0 90)
			(unlocked yes)
			(layer "B.Fab")
			(hide yes)
			(effects
				(font
					(size 1 1)
					(thickness 0.15)
				)
				(justify mirror)
			)
		)
		(property "Author" "Antmicro"
			(at 0 0 90)
			(unlocked yes)
			(layer "B.Fab")
			(hide yes)
			(effects
				(font
					(size 1 1)
					(thickness 0.15)
				)
				(justify mirror)
			)
		)
		(property "Voltage" "100V"
			(at 0 0 90)
			(unlocked yes)
			(layer "B.Fab")
			(hide yes)
			(effects
				(font
					(size 1 1)
					(thickness 0.15)
				)
				(justify mirror)
			)
		)
		(property "Dielectric" "X7S"
			(at 0 0 90)
			(unlocked yes)
			(layer "B.Fab")
			(hide yes)
			(effects
				(font
					(size 1 1)
					(thickness 0.15)
				)
				(justify mirror)
			)
		)
		(property "Public" "False"
			(at 0 0 90)
			(unlocked yes)
			(layer "B.Fab")
			(hide yes)
			(effects
				(font
					(size 1 1)
					(thickness 0.15)
				)
				(justify mirror)
			)
		)
		(sheetname "/Ethernet/")
		(sheetfile "ethernet.kicad_sch")
		(attr smd)
		(fp_line
			(start -1.415 -2.61)
			(end 1.415 -2.61)
			(stroke
				(width 0.15)
				(type solid)
			)
			(layer "B.SilkS")
		)
		(fp_line
			(start -1.415 2.61)
			(end 1.415 2.61)
			(stroke
				(width 0.15)
				(type solid)
			)
			(layer "B.SilkS")
		)
		(fp_rect
			(start -3.7 2.95)
			(end 3.7 -2.95)
			(stroke
				(width 0.05)
				(type solid)
			)
			(fill no)
			(layer "B.CrtYd")
		)
		(fp_rect
			(start -2.85 2.5)
			(end 2.85 -2.5)
			(stroke
				(width 0.15)
				(type solid)
			)
			(fill no)
			(layer "B.Fab")
		)
		(fp_text user "License: Apache-2.0"
			(at -3.7 -6.9 270)
			(layer "B.Fab")
			(effects
				(font
					(size 0.7 0.7)
					(thickness 0.15)
				)
				(justify left bottom mirror)
			)
		)
		(fp_text user "${REFERENCE}"
			(at -3.7 -5.9 270)
			(layer "B.Fab")
			(effects
				(font
					(size 0.7 0.7)
					(thickness 0.15)
				)
				(justify left bottom mirror)
			)
		)
		(fp_text user "Author: Antmicro"
			(at -3.7 -7.9 270)
			(layer "B.Fab")
			(effects
				(font
					(size 0.7 0.7)
					(thickness 0.15)
				)
				(justify left bottom mirror)
			)
		)
		(pad "1" smd roundrect
			(at -2.55 0 90)
			(size 1.8 5.4)
			(layers "B.Cu" "B.Mask" "B.Paste")
			(roundrect_rratio 0.138889)
			(net 1 "GNDD")
			(pintype "passive")
		)
		(pad "2" smd roundrect
			(at 2.55 0 90)
			(size 1.8 5.4)
			(layers "B.Cu" "B.Mask" "B.Paste")
			(roundrect_rratio 0.138889)
			(net 33 "/Ethernet/VDD")
			(pintype "passive")
		)
	)
	(footprint "antmicro-footprints:R_0402_1005Metric"
		(layer "B.Cu")
		(at 72.55 150.6365 -90)
		(descr "Resistor SMD 0402")
		(tags "resistor SMD 0402")
		(property "Reference" "R262"
			(at -3.8 -0.45 90)
			(layer "B.SilkS")
			(effects
				(font
					(size 0.7 0.7)
					(thickness 0.15)
				)
				(justify left bottom mirror)
			)
		)
		(property "Value" "R_100k_0402"
			(at -1.011843 -1.772047 90)
			(layer "B.Fab")
			(effects
				(font
					(size 0.7 0.7)
					(thickness 0.15)
				)
				(justify left bottom mirror)
			)
		)
		(property "Datasheet" "https://www.bourns.com/docs/product-datasheets/cr.pdf"
			(at 0 0 270)
			(layer "B.Fab")
			(hide yes)
			(effects
				(font
					(size 1.27 1.27)
					(thickness 0.15)
				)
			)
		)
		(property "Manufacturer" "Bourns"
			(at 0 0 270)
			(unlocked yes)
			(layer "B.Fab")
			(hide yes)
			(effects
				(font
					(size 1 1)
					(thickness 0.15)
				)
				(justify mirror)
			)
		)
		(property "MPN" "CR0402-FX-1003GLF"
			(at 0 0 270)
			(unlocked yes)
			(layer "B.Fab")
			(hide yes)
			(effects
				(font
					(size 1 1)
					(thickness 0.15)
				)
				(justify mirror)
			)
		)
		(property "Val" "100k"
			(at 0 0 270)
			(unlocked yes)
			(layer "B.Fab")
			(hide yes)
			(effects
				(font
					(size 1 1)
					(thickness 0.15)
				)
				(justify mirror)
			)
		)
		(property "License" "Apache-2.0"
			(at 0 0 270)
			(unlocked yes)
			(layer "B.Fab")
			(hide yes)
			(effects
				(font
					(size 1 1)
					(thickness 0.15)
				)
				(justify mirror)
			)
		)
		(property "Author" "Antmicro"
			(at 0 0 270)
			(unlocked yes)
			(layer "B.Fab")
			(hide yes)
			(effects
				(font
					(size 1 1)
					(thickness 0.15)
				)
				(justify mirror)
			)
		)
		(property "Tolerance" "1%"
			(at 0 0 270)
			(unlocked yes)
			(layer "B.Fab")
			(hide yes)
			(effects
				(font
					(size 1 1)
					(thickness 0.15)
				)
				(justify mirror)
			)
		)
		(sheetname "/Compute module/")
		(sheetfile "compute-module.kicad_sch")
		(attr smd)
		(fp_rect
			(start -0.925 0.47)
			(end 0.925 -0.47)
			(stroke
				(width 0.05)
				(type default)
			)
			(fill no)
			(layer "B.CrtYd")
		)
		(fp_rect
			(start -0.5 0.25)
			(end 0.5 -0.25)
			(stroke
				(width 0.15)
				(type solid)
			)
			(fill no)
			(layer "B.Fab")
		)
		(fp_text user "Author: Antmicro"
			(at -0.95 -4.169 90)
			(layer "B.Fab")
			(effects
				(font
					(size 0.7 0.7)
					(thickness 0.15)
				)
				(justify left bottom mirror)
			)
		)
		(fp_text user "License: Apache-2.0"
			(at -0.95 -5.169 90)
			(layer "B.Fab")
			(effects
				(font
					(size 0.7 0.7)
					(thickness 0.15)
				)
				(justify left bottom mirror)
			)
		)
		(fp_text user "${REFERENCE}"
			(at -0.95 -3.168 90)
			(layer "B.Fab")
			(effects
				(font
					(size 0.7 0.7)
					(thickness 0.15)
				)
				(justify left bottom mirror)
			)
		)
		(pad "1" smd roundrect
			(at -0.48 0 270)
			(size 0.59 0.64)
			(layers "B.Cu" "B.Mask" "B.Paste")
			(roundrect_rratio 0.25)
			(net 3 "GND")
			(pintype "passive")
		)
		(pad "2" smd roundrect
			(at 0.48 0 270)
			(size 0.59 0.64)
			(layers "B.Cu" "B.Mask" "B.Paste")
			(roundrect_rratio 0.25)
			(net 22 "+1V8")
			(pintype "passive")
		)
	)
)
